# T6G (Grand Teton) — schematic netlist excerpt (pin names and nets, part order shuffled) for the footprints in the layout excerpt that follows; sources: Cadence DE-HDL packaged netlist, KiCad conversion of 04192023_DAF0TMB3IC0_F0TG_MB_C_brd_V02_OCP.brd

X9026  TP_TDR_4P_FTS  TP_TDR_4P_DIP EMPTY  pkg TH  page 261
  S1  = TDR_DIFF_85_NECK_IN6_DP
  P1  = T1_GND
  P2  = T1_GND
  S2  = TDR_DIFF_85_NECK_IN6_DN

R289  Q_RES  33 5% CHIP  pkg 0402LF  page 81 : A = PVDD18_S5_P1_EN ; B = PVDD18_S5_P1_R_EN

(kicad_pcb
	(version 20260206)
	(generator "pcbnew")
	(generator_version "10.0")
	(general
		(thickness 1.6)
		(legacy_teardrops no)
	)
	(paper "A4")
	(title_block
		(title "04192023_DAF0TMB3IC0_F0TG_MB_C_brd_V02_OCP.brd")
		(comment 1 "Grand Teton / footprints 7885-7886 of 8354")
	)
	(layers
		(0 "F.Cu" signal "TOP")
		(4 "In1.Cu" signal "GND")
		(6 "In2.Cu" signal "IN1")
		(8 "In3.Cu" signal "GND1")
		(10 "In4.Cu" signal "IN2")
		(12 "In5.Cu" signal "GND2")
		(14 "In6.Cu" signal "IN3")
		(16 "In7.Cu" signal "GND3")
		(18 "In8.Cu" signal "VCC")
		(20 "In9.Cu" signal "VCC1")
		(22 "In10.Cu" signal "GND4")
		(24 "In11.Cu" signal "IN4")
		(26 "In12.Cu" signal "GND5")
		(28 "In13.Cu" signal "IN5")
		(30 "In14.Cu" signal "GND6")
		(32 "In15.Cu" signal "IN6")
		(34 "In16.Cu" signal "GND7")
		(2 "B.Cu" signal "BOTTOM")
		(9 "F.Adhes" user "F.Adhesive")
		(11 "B.Adhes" user "B.Adhesive")
		(13 "F.Paste" user "Package Geometry/Pastemask Top")
		(15 "B.Paste" user "Package Geometry/Pastemask Bottom")
		(5 "F.SilkS" user "Ref Des/Silkscreen Top")
		(7 "B.SilkS" user "Ref Des/Silkscreen Bottom")
		(1 "F.Mask" user "Board Geometry/Soldermask Top")
		(3 "B.Mask" user "Board Geometry/Soldermask Bottom")
		(17 "Dwgs.User" user "User.Drawings")
		(19 "Cmts.User" user "User.Comments")
		(21 "Eco1.User" user "User.Eco1")
		(23 "Eco2.User" user "User.Eco2")
		(25 "Edge.Cuts" user "Board Geometry/Outline")
		(27 "Margin" user)
		(31 "F.CrtYd" user "Package Geometry/Place Bound Top")
		(29 "B.CrtYd" user "Package Geometry/Place Bound Bottom")
		(35 "F.Fab" user "Ref Des/Assembly Top")
		(33 "B.Fab" user "Ref Des/Assembly Bottom")
	)
	(footprint ""
		(layer "B.Cu")
		(at 490.160564 -457.29144 -90)
		(property "Reference" "X9026"
			(at 4.7244 -1.61163 270)
			(unlocked yes)
			(layer "B.SilkS")
			(effects
				(font
					(size 0.7874 0.5842)
					(thickness 0.1524)
				)
				(justify left mirror)
			)
		)
		(property "Value" ""
			(at 0 0 90)
			(layer "B.Fab")
			(effects
				(font
					(size 1.27 1.27)
				)
				(justify mirror)
			)
		)
		(property "User Part Number" "N_A"
			(at -1.30175 1.27 180)
			(unlocked yes)
			(layer "Cmts.User")
			(hide yes)
			(effects
				(font
					(size 0.635 0.4064)
					(thickness 0.1524)
				)
				(justify mirror)
			)
		)
		(property "Device Type" "TP_TDR_4P_FTS_TH-TP_TDR_4P_DIP,EMPTY,TP15"
			(at -1.30175 1.27 180)
			(unlocked yes)
			(layer "B.Fab")
			(hide yes)
			(effects
				(font
					(size 0.635 0.4064)
					(thickness 0.1524)
				)
				(justify mirror)
			)
		)
		(duplicate_pad_numbers_are_jumpers no)
		(fp_line
			(start -2.54 3.81)
			(end -2.54 3.6703)
			(stroke
				(width 0.1524)
				(type default)
			)
			(layer "B.SilkS")
		)
		(fp_line
			(start 0 3.81)
			(end -2.54 3.81)
			(stroke
				(width 0.1524)
				(type default)
			)
			(layer "B.SilkS")
		)
		(fp_line
			(start 0 3.175)
			(end 0 3.81)
			(stroke
				(width 0.1524)
				(type default)
			)
			(layer "B.SilkS")
		)
		(fp_line
			(start -2.54 1.4097)
			(end -2.54 1.1303)
			(stroke
				(width 0.1524)
				(type default)
			)
			(layer "B.SilkS")
		)
		(fp_line
			(start 0 0.635)
			(end 0 1.905)
			(stroke
				(width 0.1524)
				(type default)
			)
			(layer "B.SilkS")
		)
		(fp_line
			(start -2.54 -1.1303)
			(end -2.54 -1.27)
			(stroke
				(width 0.1524)
				(type default)
			)
			(layer "B.SilkS")
		)
		(fp_line
			(start -2.54 -1.27)
			(end 0 -1.27)
			(stroke
				(width 0.1524)
				(type default)
			)
			(layer "B.SilkS")
		)
		(fp_line
			(start 0 -1.27)
			(end 0 -0.635)
			(stroke
				(width 0.1524)
				(type default)
			)
			(layer "B.SilkS")
		)
		(fp_poly
			(pts
				(xy 0.761746 0) (xy 2.285746 -0.762) (xy 2.285746 0.762)
			)
			(stroke
				(width 0)
				(type default)
			)
			(fill yes)
			(layer "B.SilkS")
		)
		(fp_line
			(start -2.54 3.81)
			(end -2.54 -1.27)
			(stroke
				(width 0.1)
				(type default)
			)
			(layer "B.Fab")
		)
		(fp_line
			(start 0 3.81)
			(end -2.54 3.81)
			(stroke
				(width 0.1)
				(type default)
			)
			(layer "B.Fab")
		)
		(fp_line
			(start -2.54 -1.27)
			(end 0 -1.27)
			(stroke
				(width 0.1)
				(type default)
			)
			(layer "B.Fab")
		)
		(fp_line
			(start 0 -1.27)
			(end 0 3.81)
			(stroke
				(width 0.1)
				(type default)
			)
			(layer "B.Fab")
		)
		(fp_poly
			(pts
				(xy 0.761746 0) (xy 2.285746 -0.762) (xy 2.285746 0.762)
			)
			(stroke
				(width 0)
				(type default)
			)
			(fill yes)
			(layer "B.Fab")
		)
		(pad "1" thru_hole circle
			(at 0 0 90)
			(size 1.0033 1.0033)
			(drill 0.249936)
			(layers "*.Cu" "*.Mask")
			(remove_unused_layers no)
			(net "TDR_DIFF_85_NECK_IN6_DP")
			(clearance 0.10795)
			(padstack
				(mode front_inner_back)
				(layer "Inner"
					(shape circle)
					(size 0.8001 0.8001)
					(clearance 0.1524)
				)
				(layer "B.Cu"
					(shape circle)
					(size 1.0033 1.0033)
					(thermal_gap 0.10795)
					(clearance 0.10795)
				)
			)
		)
		(pad "2" thru_hole circle
			(at -2.54 0 90)
			(size 1.9939 1.9939)
			(drill 0.249936)
			(layers "*.Cu" "*.Mask")
			(remove_unused_layers no)
			(net "T1_GND")
			(clearance 0.10795)
			(padstack
				(mode front_inner_back)
				(layer "Inner"
					(shape circle)
					(size 0.8001 0.8001)
					(clearance 0.1524)
				)
				(layer "B.Cu"
					(shape circle)
					(size 1.9939 1.9939)
					(thermal_gap 0.10795)
					(clearance 0.10795)
				)
			)
		)
		(pad "3" thru_hole circle
			(at -2.54 2.54 90)
			(size 1.9939 1.9939)
			(drill 0.249936)
			(layers "*.Cu" "*.Mask")
			(remove_unused_layers no)
			(net "T1_GND")
			(clearance 0.10795)
			(padstack
				(mode front_inner_back)
				(layer "Inner"
					(shape circle)
					(size 0.8001 0.8001)
					(clearance 0.1524)
				)
				(layer "B.Cu"
					(shape circle)
					(size 1.9939 1.9939)
					(thermal_gap 0.10795)
					(clearance 0.10795)
				)
			)
		)
		(pad "4" thru_hole circle
			(at 0 2.54 90)
			(size 1.0033 1.0033)
			(drill 0.249936)
			(layers "*.Cu" "*.Mask")
			(remove_unused_layers no)
			(net "TDR_DIFF_85_NECK_IN6_DN")
			(clearance 0.10795)
			(padstack
				(mode front_inner_back)
				(layer "Inner"
					(shape circle)
					(size 0.8001 0.8001)
					(clearance 0.1524)
				)
				(layer "B.Cu"
					(shape circle)
					(size 1.0033 1.0033)
					(thermal_gap 0.10795)
					(clearance 0.10795)
				)
			)
		)
	)
	(footprint ""
		(layer "B.Cu")
		(at 197.269608 -106.513376)
		(property "Reference" "R289"
			(at 0 0 0)
			(layer "B.SilkS")
			(hide yes)
			(effects
				(font
					(size 1.27 1.27)
				)
				(justify mirror)
			)
		)
		(property "Value" ""
			(at 0 0 0)
			(layer "B.Fab")
			(effects
				(font
					(size 1.27 1.27)
				)
				(justify mirror)
			)
		)
		(duplicate_pad_numbers_are_jumpers no)
		(fp_line
			(start -0.7874 -0.4064)
			(end -0.7874 0.4064)
			(stroke
				(width 0.1524)
				(type default)
			)
			(layer "B.SilkS")
		)
		(fp_line
			(start -0.7874 0.4064)
			(end 0.7874 0.4064)
			(stroke
				(width 0.1524)
				(type default)
			)
			(layer "B.SilkS")
		)
		(fp_line
			(start 0.7874 -0.4064)
			(end -0.7874 -0.4064)
			(stroke
				(width 0.1524)
				(type default)
			)
			(layer "B.SilkS")
		)
		(fp_line
			(start 0.7874 0.4064)
			(end 0.7874 -0.4064)
			(stroke
				(width 0.1524)
				(type default)
			)
			(layer "B.SilkS")
		)
		(fp_line
			(start -0.67945 -0.3048)
			(end -0.67945 0.3048)
			(stroke
				(width 0.1)
				(type default)
			)
			(layer "B.Fab")
		)
		(fp_line
			(start -0.67945 0.3048)
			(end -0.120396 0.3048)
			(stroke
				(width 0.1)
				(type default)
			)
			(layer "B.Fab")
		)
		(fp_line
			(start -0.12065 -0.3048)
			(end -0.67945 -0.3048)
			(stroke
				(width 0.1)
				(type default)
			)
			(layer "B.Fab")
		)
		(fp_line
			(start -0.12065 -0.2794)
			(end -0.12065 -0.3048)
			(stroke
				(width 0.1)
				(type default)
			)
			(layer "B.Fab")
		)
		(fp_line
			(start -0.120396 0.2794)
			(end 0.12065 0.2794)
			(stroke
				(width 0.1)
				(type default)
			)
			(layer "B.Fab")
		)
		(fp_line
			(start -0.120396 0.3048)
			(end -0.120396 0.2794)
			(stroke
				(width 0.1)
				(type default)
			)
			(layer "B.Fab")
		)
		(fp_line
			(start 0.12065 -0.305054)
			(end 0.12065 -0.2794)
			(stroke
				(width 0.1)
				(type default)
			)
			(layer "B.Fab")
		)
		(fp_line
			(start 0.12065 -0.2794)
			(end -0.12065 -0.2794)
			(stroke
				(width 0.1)
				(type default)
			)
			(layer "B.Fab")
		)
		(fp_line
			(start 0.12065 0.2794)
			(end 0.12065 0.3048)
			(stroke
				(width 0.1)
				(type default)
			)
			(layer "B.Fab")
		)
		(fp_line
			(start 0.12065 0.3048)
			(end 0.67945 0.3048)
			(stroke
				(width 0.1)
				(type default)
			)
			(layer "B.Fab")
		)
		(fp_line
			(start 0.67945 -0.305054)
			(end 0.12065 -0.305054)
			(stroke
				(width 0.1)
				(type default)
			)
			(layer "B.Fab")
		)
		(fp_line
			(start 0.67945 0.3048)
			(end 0.67945 -0.305054)
			(stroke
				(width 0.1)
				(type default)
			)
			(layer "B.Fab")
		)
		(pad "1" smd circle
			(at 0.40005 0 180)
			(size 0 0)
			(layers "B.Cu" "B.Mask" "B.Paste")
			(net "PVDD18_S5_P1_EN")
		)
		(pad "2" smd circle
			(at -0.40005 0 180)
			(size 0 0)
			(layers "B.Cu" "B.Mask" "B.Paste")
			(net "PVDD18_S5_P1_R_EN")
		)
	)
)
